(kicad_pcb
	(version 20260206)
	(generator "pcbnew")
	(generator_version "10.0")
	(general
		(thickness 1.6)
		(legacy_teardrops no)
	)
	(paper "A4")
	(title_block
		(title "12092022_DA0F0TFB6D0_F0T_FAN_BOARD_MP5048_D_brd_v02_OCP.brd")
		(comment 1 "Grand Teton / footprints 492-496 of 924")
	)
	(layers
		(0 "F.Cu" signal "TOP")
		(4 "In1.Cu" signal "GND")
		(6 "In2.Cu" signal "IN1")
		(8 "In3.Cu" signal "IN2")
		(10 "In4.Cu" signal "GND1")
		(2 "B.Cu" signal "BOTTOM")
		(9 "F.Adhes" user "F.Adhesive")
		(11 "B.Adhes" user "B.Adhesive")
		(13 "F.Paste" user "Package Geometry/Pastemask Top")
		(15 "B.Paste" user "Package Geometry/Pastemask Bottom")
		(5 "F.SilkS" user "Ref Des/Silkscreen Top")
		(7 "B.SilkS" user "Ref Des/Silkscreen Bottom")
		(1 "F.Mask" user "Board Geometry/Soldermask Top")
		(3 "B.Mask" user "Board Geometry/Soldermask Bottom")
		(17 "Dwgs.User" user "User.Drawings")
		(19 "Cmts.User" user "User.Comments")
		(21 "Eco1.User" user "User.Eco1")
		(23 "Eco2.User" user "User.Eco2")
		(25 "Edge.Cuts" user "Board Geometry/Outline")
		(27 "Margin" user)
		(31 "F.CrtYd" user "Package Geometry/Place Bound Top")
		(29 "B.CrtYd" user "Package Geometry/Place Bound Bottom")
		(35 "F.Fab" user "Ref Des/Assembly Top")
		(33 "B.Fab" user "Ref Des/Assembly Bottom")
	)
	(footprint ""
		(layer "F.Cu")
		(at 36.322 -189.484)
		(property "Reference" "U389"
			(at -0.635 3.20167 0)
			(unlocked yes)
			(layer "F.SilkS")
			(effects
				(font
					(size 0.7874 0.5842)
					(thickness 0.1524)
				)
				(justify left)
			)
		)
		(property "Value" ""
			(at 0 0 0)
			(layer "F.Fab")
			(effects
				(font
					(size 1.27 1.27)
				)
			)
		)
		(duplicate_pad_numbers_are_jumpers no)
		(fp_line
			(start -2.0066 -2.5527)
			(end -0.5715 -2.5527)
			(stroke
				(width 0.1524)
				(type default)
			)
			(layer "F.SilkS")
		)
		(fp_line
			(start -2.0066 2.5527)
			(end -2.0066 -2.5527)
			(stroke
				(width 0.1524)
				(type default)
			)
			(layer "F.SilkS")
		)
		(fp_line
			(start -0.5715 -2.5527)
			(end 0 -1.9812)
			(stroke
				(width 0.1524)
				(type default)
			)
			(layer "F.SilkS")
		)
		(fp_line
			(start 0 -1.9812)
			(end 0.5715 -2.5527)
			(stroke
				(width 0.1524)
				(type default)
			)
			(layer "F.SilkS")
		)
		(fp_line
			(start 0.5715 -2.5527)
			(end 2.0066 -2.5527)
			(stroke
				(width 0.1524)
				(type default)
			)
			(layer "F.SilkS")
		)
		(fp_line
			(start 2.0066 -2.5527)
			(end 2.0066 2.5527)
			(stroke
				(width 0.1524)
				(type default)
			)
			(layer "F.SilkS")
		)
		(fp_line
			(start 2.0066 2.5527)
			(end -2.0066 2.5527)
			(stroke
				(width 0.1524)
				(type default)
			)
			(layer "F.SilkS")
		)
		(fp_poly
			(pts
				(xy -4.36372 -1.608328) (xy -4.36372 -2.233168) (xy -3.81 -1.905)
			)
			(stroke
				(width 0)
				(type default)
			)
			(fill yes)
			(layer "F.SilkS")
		)
		(fp_line
			(start -2.249932 -2.549906)
			(end 2.249932 -2.549906)
			(stroke
				(width 0.1)
				(type default)
			)
			(layer "F.Fab")
		)
		(fp_line
			(start -2.249932 2.549906)
			(end -2.249932 -2.549906)
			(stroke
				(width 0.1)
				(type default)
			)
			(layer "F.Fab")
		)
		(fp_line
			(start 2.249932 -2.549906)
			(end 2.249932 2.549906)
			(stroke
				(width 0.1)
				(type default)
			)
			(layer "F.Fab")
		)
		(fp_line
			(start 2.249932 2.549906)
			(end -2.249932 2.549906)
			(stroke
				(width 0.1)
				(type default)
			)
			(layer "F.Fab")
		)
		(fp_poly
			(pts
				(xy -4.36372 -1.608328) (xy -4.36372 -2.233168) (xy -3.81 -1.905)
			)
			(stroke
				(width 0)
				(type default)
			)
			(fill yes)
			(layer "F.Fab")
		)
		(pad "1" smd rect
			(at -2.921 -1.949958 270)
			(size 0.3556 1.4986)
			(layers "F.Cu" "F.Mask" "F.Paste")
			(net "P52V_FAN_BUFF_EN_R")
		)
		(pad "2" smd rect
			(at -2.921 -1.299972 270)
			(size 0.3556 1.4986)
			(layers "F.Cu" "F.Mask" "F.Paste")
			(net "P52V_FAN_4_BUFF_EN")
		)
		(pad "3" smd rect
			(at -2.921 -0.649986 270)
			(size 0.3556 1.4986)
			(layers "F.Cu" "F.Mask" "F.Paste")
			(net "P52V_FAN_BUFF_EN_R")
		)
		(pad "4" smd rect
			(at -2.921 0 270)
			(size 0.3556 1.4986)
			(layers "F.Cu" "F.Mask" "F.Paste")
			(net "P52V_FAN_5_BUFF_EN")
		)
		(pad "5" smd rect
			(at -2.921 0.649986 270)
			(size 0.3556 1.4986)
			(layers "F.Cu" "F.Mask" "F.Paste")
			(net "P52V_FAN_BUFF_EN_R")
		)
		(pad "6" smd rect
			(at -2.921 1.299972 270)
			(size 0.3556 1.4986)
			(layers "F.Cu" "F.Mask" "F.Paste")
			(net "P52V_FAN_6_BUFF_EN")
		)
		(pad "7" smd rect
			(at -2.921 1.949958 270)
			(size 0.3556 1.4986)
			(layers "F.Cu" "F.Mask" "F.Paste")
			(net "GND")
		)
		(pad "8" smd rect
			(at 2.921 1.949958 270)
			(size 0.3556 1.4986)
			(layers "F.Cu" "F.Mask" "F.Paste")
			(net "P52V_FAN_7_BUFF_EN")
		)
		(pad "9" smd rect
			(at 2.921 1.299972 270)
			(size 0.3556 1.4986)
			(layers "F.Cu" "F.Mask" "F.Paste")
			(net "P52V_FAN_BUFF_EN_R")
		)
		(pad "10" smd rect
			(at 2.921 0.649986 270)
			(size 0.3556 1.4986)
			(layers "F.Cu" "F.Mask" "F.Paste")
			(net "NC_U389_E")
		)
		(pad "11" smd rect
			(at 2.921 0 270)
			(size 0.3556 1.4986)
			(layers "F.Cu" "F.Mask" "F.Paste")
			(net "PD_FAN_BUFF_INPUT_U337E")
		)
		(pad "12" smd rect
			(at 2.921 -0.649986 270)
			(size 0.3556 1.4986)
			(layers "F.Cu" "F.Mask" "F.Paste")
			(net "NC_U389_F")
		)
		(pad "13" smd rect
			(at 2.921 -1.299972 270)
			(size 0.3556 1.4986)
			(layers "F.Cu" "F.Mask" "F.Paste")
			(net "PD_FAN_BUFF_INPUT_U337F")
		)
		(pad "14" smd rect
			(at 2.921 -1.949958 270)
			(size 0.3556 1.4986)
			(layers "F.Cu" "F.Mask" "F.Paste")
			(net "P3V3_AUX")
		)
	)
	(footprint ""
		(layer "F.Cu")
		(at 23.495 -215.265 90)
		(property "Reference" "R5668"
			(at 0 0 90)
			(layer "F.SilkS")
			(hide yes)
			(effects
				(font
					(size 1.27 1.27)
				)
			)
		)
		(property "Value" ""
			(at 0 0 90)
			(layer "F.Fab")
			(effects
				(font
					(size 1.27 1.27)
				)
			)
		)
		(duplicate_pad_numbers_are_jumpers no)
		(fp_line
			(start 0.7874 -0.4064)
			(end 0.7874 0.4064)
			(stroke
				(width 0.1524)
				(type default)
			)
			(layer "F.SilkS")
		)
		(fp_line
			(start -0.7874 -0.4064)
			(end 0.7874 -0.4064)
			(stroke
				(width 0.1524)
				(type default)
			)
			(layer "F.SilkS")
		)
		(fp_line
			(start 0.7874 0.4064)
			(end -0.7874 0.4064)
			(stroke
				(width 0.1524)
				(type default)
			)
			(layer "F.SilkS")
		)
		(fp_line
			(start -0.7874 0.4064)
			(end -0.7874 -0.4064)
			(stroke
				(width 0.1524)
				(type default)
			)
			(layer "F.SilkS")
		)
		(fp_line
			(start -0.12065 -0.305054)
			(end -0.12065 -0.2794)
			(stroke
				(width 0.1)
				(type default)
			)
			(layer "F.Fab")
		)
		(fp_line
			(start -0.67945 -0.305054)
			(end -0.12065 -0.305054)
			(stroke
				(width 0.1)
				(type default)
			)
			(layer "F.Fab")
		)
		(fp_line
			(start 0.67945 -0.3048)
			(end 0.67945 0.3048)
			(stroke
				(width 0.1)
				(type default)
			)
			(layer "F.Fab")
		)
		(fp_line
			(start 0.12065 -0.3048)
			(end 0.67945 -0.3048)
			(stroke
				(width 0.1)
				(type default)
			)
			(layer "F.Fab")
		)
		(fp_line
			(start 0.12065 -0.2794)
			(end 0.12065 -0.3048)
			(stroke
				(width 0.1)
				(type default)
			)
			(layer "F.Fab")
		)
		(fp_line
			(start -0.12065 -0.2794)
			(end 0.12065 -0.2794)
			(stroke
				(width 0.1)
				(type default)
			)
			(layer "F.Fab")
		)
		(fp_line
			(start 0.120396 0.2794)
			(end -0.12065 0.2794)
			(stroke
				(width 0.1)
				(type default)
			)
			(layer "F.Fab")
		)
		(fp_line
			(start -0.12065 0.2794)
			(end -0.12065 0.3048)
			(stroke
				(width 0.1)
				(type default)
			)
			(layer "F.Fab")
		)
		(fp_line
			(start 0.67945 0.3048)
			(end 0.120396 0.3048)
			(stroke
				(width 0.1)
				(type default)
			)
			(layer "F.Fab")
		)
		(fp_line
			(start 0.120396 0.3048)
			(end 0.120396 0.2794)
			(stroke
				(width 0.1)
				(type default)
			)
			(layer "F.Fab")
		)
		(fp_line
			(start -0.12065 0.3048)
			(end -0.67945 0.3048)
			(stroke
				(width 0.1)
				(type default)
			)
			(layer "F.Fab")
		)
		(fp_line
			(start -0.67945 0.3048)
			(end -0.67945 -0.305054)
			(stroke
				(width 0.1)
				(type default)
			)
			(layer "F.Fab")
		)
		(pad "1" smd circle
			(at -0.40005 0 90)
			(size 0 0)
			(layers "F.Cu" "F.Mask" "F.Paste")
			(net "FAN_6_PRESENT")
		)
		(pad "2" smd circle
			(at 0.40005 0 90)
			(size 0 0)
			(layers "F.Cu" "F.Mask" "F.Paste")
			(net "GND")
		)
	)
	(footprint ""
		(layer "F.Cu")
		(at 40.127428 -66.986912 180)
		(property "Reference" "C172"
			(at 0 0 180)
			(layer "F.SilkS")
			(hide yes)
			(effects
				(font
					(size 1.27 1.27)
				)
			)
		)
		(property "Value" ""
			(at 0 0 180)
			(layer "F.Fab")
			(effects
				(font
					(size 1.27 1.27)
				)
			)
		)
		(duplicate_pad_numbers_are_jumpers no)
		(fp_line
			(start 0.7874 0.4064)
			(end -0.7874 0.4064)
			(stroke
				(width 0.1524)
				(type default)
			)
			(layer "F.SilkS")
		)
		(fp_line
			(start 0.7874 -0.4064)
			(end 0.7874 0.4064)
			(stroke
				(width 0.1524)
				(type default)
			)
			(layer "F.SilkS")
		)
		(fp_line
			(start -0.7874 0.4064)
			(end -0.7874 -0.4064)
			(stroke
				(width 0.1524)
				(type default)
			)
			(layer "F.SilkS")
		)
		(fp_line
			(start -0.7874 -0.4064)
			(end 0.7874 -0.4064)
			(stroke
				(width 0.1524)
				(type default)
			)
			(layer "F.SilkS")
		)
		(fp_line
			(start 0.67945 0.3048)
			(end 0.120396 0.3048)
			(stroke
				(width 0.1)
				(type default)
			)
			(layer "F.Fab")
		)
		(fp_line
			(start 0.67945 -0.3048)
			(end 0.67945 0.3048)
			(stroke
				(width 0.1)
				(type default)
			)
			(layer "F.Fab")
		)
		(fp_line
			(start 0.12065 -0.2794)
			(end 0.12065 -0.3048)
			(stroke
				(width 0.1)
				(type default)
			)
			(layer "F.Fab")
		)
		(fp_line
			(start 0.12065 -0.3048)
			(end 0.67945 -0.3048)
			(stroke
				(width 0.1)
				(type default)
			)
			(layer "F.Fab")
		)
		(fp_line
			(start 0.120396 0.3048)
			(end 0.120396 0.2794)
			(stroke
				(width 0.1)
				(type default)
			)
			(layer "F.Fab")
		)
		(fp_line
			(start 0.120396 0.2794)
			(end -0.12065 0.2794)
			(stroke
				(width 0.1)
				(type default)
			)
			(layer "F.Fab")
		)
		(fp_line
			(start -0.12065 0.3048)
			(end -0.67945 0.3048)
			(stroke
				(width 0.1)
				(type default)
			)
			(layer "F.Fab")
		)
		(fp_line
			(start -0.12065 0.2794)
			(end -0.12065 0.3048)
			(stroke
				(width 0.1)
				(type default)
			)
			(layer "F.Fab")
		)
		(fp_line
			(start -0.12065 -0.2794)
			(end 0.12065 -0.2794)
			(stroke
				(width 0.1)
				(type default)
			)
			(layer "F.Fab")
		)
		(fp_line
			(start -0.12065 -0.305054)
			(end -0.12065 -0.2794)
			(stroke
				(width 0.1)
				(type default)
			)
			(layer "F.Fab")
		)
		(fp_line
			(start -0.67945 0.3048)
			(end -0.67945 -0.305054)
			(stroke
				(width 0.1)
				(type default)
			)
			(layer "F.Fab")
		)
		(fp_line
			(start -0.67945 -0.305054)
			(end -0.12065 -0.305054)
			(stroke
				(width 0.1)
				(type default)
			)
			(layer "F.Fab")
		)
		(pad "1" smd circle
			(at -0.40005 0 180)
			(size 0 0)
			(layers "F.Cu" "F.Mask" "F.Paste")
			(net "P3V3_AUX")
		)
		(pad "2" smd circle
			(at 0.40005 0 180)
			(size 0 0)
			(layers "F.Cu" "F.Mask" "F.Paste")
			(net "GND")
		)
	)
	(footprint ""
		(layer "F.Cu")
		(at 14.859 -134.874)
		(property "Reference" "R5619"
			(at 0 0 0)
			(layer "F.SilkS")
			(hide yes)
			(effects
				(font
					(size 1.27 1.27)
				)
			)
		)
		(property "Value" ""
			(at 0 0 0)
			(layer "F.Fab")
			(effects
				(font
					(size 1.27 1.27)
				)
			)
		)
		(duplicate_pad_numbers_are_jumpers no)
		(fp_line
			(start -0.7874 -0.4064)
			(end 0.7874 -0.4064)
			(stroke
				(width 0.1524)
				(type default)
			)
			(layer "F.SilkS")
		)
		(fp_line
			(start -0.7874 0.4064)
			(end -0.7874 -0.4064)
			(stroke
				(width 0.1524)
				(type default)
			)
			(layer "F.SilkS")
		)
		(fp_line
			(start 0.7874 -0.4064)
			(end 0.7874 0.4064)
			(stroke
				(width 0.1524)
				(type default)
			)
			(layer "F.SilkS")
		)
		(fp_line
			(start 0.7874 0.4064)
			(end -0.7874 0.4064)
			(stroke
				(width 0.1524)
				(type default)
			)
			(layer "F.SilkS")
		)
		(fp_line
			(start -0.67945 -0.305054)
			(end -0.12065 -0.305054)
			(stroke
				(width 0.1)
				(type default)
			)
			(layer "F.Fab")
		)
		(fp_line
			(start -0.67945 0.3048)
			(end -0.67945 -0.305054)
			(stroke
				(width 0.1)
				(type default)
			)
			(layer "F.Fab")
		)
		(fp_line
			(start -0.12065 -0.305054)
			(end -0.12065 -0.2794)
			(stroke
				(width 0.1)
				(type default)
			)
			(layer "F.Fab")
		)
		(fp_line
			(start -0.12065 -0.2794)
			(end 0.12065 -0.2794)
			(stroke
				(width 0.1)
				(type default)
			)
			(layer "F.Fab")
		)
		(fp_line
			(start -0.12065 0.2794)
			(end -0.12065 0.3048)
			(stroke
				(width 0.1)
				(type default)
			)
			(layer "F.Fab")
		)
		(fp_line
			(start -0.12065 0.3048)
			(end -0.67945 0.3048)
			(stroke
				(width 0.1)
				(type default)
			)
			(layer "F.Fab")
		)
		(fp_line
			(start 0.120396 0.2794)
			(end -0.12065 0.2794)
			(stroke
				(width 0.1)
				(type default)
			)
			(layer "F.Fab")
		)
		(fp_line
			(start 0.120396 0.3048)
			(end 0.120396 0.2794)
			(stroke
				(width 0.1)
				(type default)
			)
			(layer "F.Fab")
		)
		(fp_line
			(start 0.12065 -0.3048)
			(end 0.67945 -0.3048)
			(stroke
				(width 0.1)
				(type default)
			)
			(layer "F.Fab")
		)
		(fp_line
			(start 0.12065 -0.2794)
			(end 0.12065 -0.3048)
			(stroke
				(width 0.1)
				(type default)
			)
			(layer "F.Fab")
		)
		(fp_line
			(start 0.67945 -0.3048)
			(end 0.67945 0.3048)
			(stroke
				(width 0.1)
				(type default)
			)
			(layer "F.Fab")
		)
		(fp_line
			(start 0.67945 0.3048)
			(end 0.120396 0.3048)
			(stroke
				(width 0.1)
				(type default)
			)
			(layer "F.Fab")
		)
		(pad "1" smd rect
			(at -0.40005 0 180)
			(size 0.4572 0.508)
			(layers "F.Cu" "F.Mask" "F.Paste")
			(net "FAN_7_PWM")
		)
		(pad "2" smd rect
			(at 0.40005 0 180)
			(size 0.4572 0.508)
			(layers "F.Cu" "F.Mask" "F.Paste")
			(net "FAN_7_PWM_R1")
		)
	)
	(footprint ""
		(layer "F.Cu")
		(at 15.377922 -16.215868 180)
		(property "Reference" "D113"
			(at 5.217922 -1.002538 0)
			(unlocked yes)
			(layer "F.SilkS")
			(effects
				(font
					(size 0.7874 0.5842)
					(thickness 0.1524)
				)
				(justify left)
			)
		)
		(property "Value" ""
			(at 0 0 180)
			(layer "F.Fab")
			(effects
				(font
					(size 1.27 1.27)
				)
			)
		)
		(duplicate_pad_numbers_are_jumpers no)
		(fp_line
			(start 2.032 0.7112)
			(end -1.651 0.7112)
			(stroke
				(width 0.1524)
				(type default)
			)
			(layer "F.SilkS")
		)
		(fp_line
			(start 2.032 -0.7112)
			(end 2.032 0.7112)
			(stroke
				(width 0.1524)
				(type default)
			)
			(layer "F.SilkS")
		)
		(fp_line
			(start 1.905 -0.6858)
			(end 1.905 0.6858)
			(stroke
				(width 0.1524)
				(type default)
			)
			(layer "F.SilkS")
		)
		(fp_line
			(start 1.778 0.6858)
			(end 1.778 -0.6858)
			(stroke
				(width 0.1524)
				(type default)
			)
			(layer "F.SilkS")
		)
		(fp_line
			(start 1.651 -0.6858)
			(end 1.651 0.6858)
			(stroke
				(width 0.1524)
				(type default)
			)
			(layer "F.SilkS")
		)
		(fp_line
			(start 0.299974 -0.500126)
			(end 0.299974 0.500126)
			(stroke
				(width 0.1524)
				(type default)
			)
			(layer "F.SilkS")
		)
		(fp_line
			(start 0.199898 0)
			(end -0.299974 -0.500126)
			(stroke
				(width 0.1524)
				(type default)
			)
			(layer "F.SilkS")
		)
		(fp_line
			(start -0.299974 0.500126)
			(end 0.199898 0)
			(stroke
				(width 0.1524)
				(type default)
			)
			(layer "F.SilkS")
		)
		(fp_line
			(start -0.299974 -0.500126)
			(end -0.299974 0.500126)
			(stroke
				(width 0.1524)
				(type default)
			)
			(layer "F.SilkS")
		)
		(fp_line
			(start -1.651 0.7112)
			(end -1.651 -0.7112)
			(stroke
				(width 0.1524)
				(type default)
			)
			(layer "F.SilkS")
		)
		(fp_line
			(start -1.651 -0.7112)
			(end 2.032 -0.7112)
			(stroke
				(width 0.1524)
				(type default)
			)
			(layer "F.SilkS")
		)
		(fp_line
			(start 1.35001 0.175006)
			(end 0.899922 0.175006)
			(stroke
				(width 0.1)
				(type default)
			)
			(layer "F.Fab")
		)
		(fp_line
			(start 1.35001 -0.225044)
			(end 1.35001 0.175006)
			(stroke
				(width 0.1)
				(type default)
			)
			(layer "F.Fab")
		)
		(fp_line
			(start 0.899922 0.700024)
			(end -0.899922 0.700024)
			(stroke
				(width 0.1)
				(type default)
			)
			(layer "F.Fab")
		)
		(fp_line
			(start 0.899922 0.175006)
			(end 0.899922 0.700024)
			(stroke
				(width 0.1)
				(type default)
			)
			(layer "F.Fab")
		)
		(fp_line
			(start 0.899922 -0.225044)
			(end 1.35001 -0.225044)
			(stroke
				(width 0.1)
				(type default)
			)
			(layer "F.Fab")
		)
		(fp_line
			(start 0.899922 -0.700024)
			(end 0.899922 -0.225044)
			(stroke
				(width 0.1)
				(type default)
			)
			(layer "F.Fab")
		)
		(fp_line
			(start 0.299974 -0.500126)
			(end 0.299974 0.500126)
			(stroke
				(width 0.1)
				(type default)
			)
			(layer "F.Fab")
		)
		(fp_line
			(start 0.199898 0)
			(end -0.299974 -0.500126)
			(stroke
				(width 0.1)
				(type default)
			)
			(layer "F.Fab")
		)
		(fp_line
			(start -0.299974 0.500126)
			(end 0.199898 0)
			(stroke
				(width 0.1)
				(type default)
			)
			(layer "F.Fab")
		)
		(fp_line
			(start -0.299974 -0.500126)
			(end -0.299974 0.500126)
			(stroke
				(width 0.1)
				(type default)
			)
			(layer "F.Fab")
		)
		(fp_line
			(start -0.899922 0.700024)
			(end -0.899922 0.175006)
			(stroke
				(width 0.1)
				(type default)
			)
			(layer "F.Fab")
		)
		(fp_line
			(start -0.899922 0.175006)
			(end -1.35001 0.175006)
			(stroke
				(width 0.1)
				(type default)
			)
			(layer "F.Fab")
		)
		(fp_line
			(start -0.899922 -0.225044)
			(end -0.899922 -0.700024)
			(stroke
				(width 0.1)
				(type default)
			)
			(layer "F.Fab")
		)
		(fp_line
			(start -0.899922 -0.700024)
			(end 0.899922 -0.700024)
			(stroke
				(width 0.1)
				(type default)
			)
			(layer "F.Fab")
		)
		(fp_line
			(start -1.35001 0.175006)
			(end -1.35001 -0.225044)
			(stroke
				(width 0.1)
				(type default)
			)
			(layer "F.Fab")
		)
		(fp_line
			(start -1.35001 -0.225044)
			(end -0.899922 -0.225044)
			(stroke
				(width 0.1)
				(type default)
			)
			(layer "F.Fab")
		)
		(fp_text user "-"
			(at 1.915922 0.452882 180)
			(unlocked yes)
			(layer "F.SilkS")
			(effects
				(font
					(size 1.905 1.4224)
					(thickness 0.1524)
				)
				(justify left)
			)
		)
		(fp_text user "+"
			(at -2.783078 0.833882 180)
			(unlocked yes)
			(layer "F.SilkS")
			(effects
				(font
					(size 1.905 1.4224)
					(thickness 0.1524)
				)
				(justify left)
			)
		)
		(fp_text user "-"
			(at 1.8288 -0.24765 180)
			(unlocked yes)
			(layer "F.Fab")
			(effects
				(font
					(size 1.905 1.4224)
					(thickness 0.1524)
				)
				(justify left)
			)
		)
		(fp_text user "+"
			(at -2.794 -0.19685 180)
			(unlocked yes)
			(layer "F.Fab")
			(effects
				(font
					(size 1.905 1.4224)
					(thickness 0.1524)
				)
				(justify left)
			)
		)
		(pad "1" smd rect
			(at -1.0922 0)
			(size 0.8128 0.8636)
			(layers "F.Cu" "F.Mask" "F.Paste")
			(net "FAN_4_TACH_IL_R")
		)
		(pad "2" smd rect
			(at 1.0922 0 180)
			(size 0.8128 0.8636)
			(layers "F.Cu" "F.Mask" "F.Paste")
			(net "FAN_4_TACH_IL_D")
		)
	)
)
